FILE_TYPE=LIBRARY_PARTS;
primitive 'RAA229621GNPHA0';
  pin
    'CS7':
      PIN_NUMBER='(23)';
      INPUT_LOAD='(-0.01,0.01)';
    'VCC':
      PIN_NUMBER='(39)';
      PINUSE='POWER';
      NO_LOAD_CHECK='Both';
      NO_IO_CHECK='Both';
      NO_ASSERT_CHECK='TRUE';
      NO_DIR_CHECK='TRUE';
      ALLOW_CONNECT='TRUE';
    'SVTI':
      PIN_NUMBER='(20)';
      INPUT_LOAD='(-0.01,0.01)';
    'PMSCL':
      PIN_NUMBER='(10)';
      INPUT_LOAD='(-0.01,0.01)';
    'SVC':
      PIN_NUMBER='(18)';
      INPUT_LOAD='(-0.01,0.01)';
    'CS6':
      PIN_NUMBER='(24)';
      INPUT_LOAD='(-0.01,0.01)';
    'SVTO':
      PIN_NUMBER='(19)';
      OUTPUT_LOAD='(1.0,-1.0)';
    'RESET_L':
      PIN_NUMBER='(14)';
      INPUT_LOAD='(-0.01,0.01)';
    'CS5':
      PIN_NUMBER='(25)';
      INPUT_LOAD='(-0.01,0.01)';
    'CS4':
      PIN_NUMBER='(26)';
      INPUT_LOAD='(-0.01,0.01)';
    'PG1':
      PIN_NUMBER='(16)';
      OUTPUT_LOAD='(1.0,-1.0)';
    'SVD':
      PIN_NUMBER='(17)';
      BIDIRECTIONAL='TRUE';
      INPUT_LOAD='(-0.01,0.01)';
      OUTPUT_LOAD='(1.0,-1.0)';
    'NPMALERT':
      PIN_NUMBER='(11)';
      OUTPUT_LOAD='(1.0,-1.0)';
    'EN0':
      PIN_NUMBER='(13)';
      INPUT_LOAD='(-0.01,0.01)';
    'RGND0':
      PIN_NUMBER='(22)';
      INPUT_LOAD='(-0.01,0.01)';
    'PMSDA':
      PIN_NUMBER='(9)';
      BIDIRECTIONAL='TRUE';
      INPUT_LOAD='(-0.01,0.01)';
      OUTPUT_LOAD='(1.0,-1.0)';
    'PWM4':
      PIN_NUMBER='(5)';
      OUTPUT_LOAD='(1.0,-1.0)';
    'PWM5':
      PIN_NUMBER='(6)';
      OUTPUT_LOAD='(1.0,-1.0)';
    'VSEN0':
      PIN_NUMBER='(21)';
      INPUT_LOAD='(-0.01,0.01)';
    'PWM1':
      PIN_NUMBER='(2)';
      OUTPUT_LOAD='(1.0,-1.0)';
    'PG0':
      PIN_NUMBER='(12)';
      OUTPUT_LOAD='(1.0,-1.0)';
    'PWM6':
      PIN_NUMBER='(7)';
      OUTPUT_LOAD='(1.0,-1.0)';
    'VCCS':
      PIN_NUMBER='(40)';
      PINUSE='POWER';
      NO_LOAD_CHECK='Both';
      NO_IO_CHECK='Both';
      NO_ASSERT_CHECK='TRUE';
      NO_DIR_CHECK='TRUE';
      ALLOW_CONNECT='TRUE';
    'VMON||IINSEN':
      PIN_NUMBER='(37)';
      INPUT_LOAD='(-0.01,0.01)';
    'VINSEN':
      PIN_NUMBER='(38)';
      INPUT_LOAD='(-0.01,0.01)';
    'TEMP0':
      PIN_NUMBER='(36)';
      INPUT_LOAD='(-0.01,0.01)';
    'VDDIO':
      PIN_NUMBER='(15)';
      INPUT_LOAD='(-0.01,0.01)';
    'VSEN1':
      PIN_NUMBER='(32)';
      INPUT_LOAD='(-0.01,0.01)';
    'RGND1':
      PIN_NUMBER='(31)';
      INPUT_LOAD='(-0.01,0.01)';
    'CS1':
      PIN_NUMBER='(29)';
      INPUT_LOAD='(-0.01,0.01)';
    'PWM7':
      PIN_NUMBER='(8)';
      OUTPUT_LOAD='(1.0,-1.0)';
    'PWM3':
      PIN_NUMBER='(4)';
      OUTPUT_LOAD='(1.0,-1.0)';
    'CS3':
      PIN_NUMBER='(27)';
      INPUT_LOAD='(-0.01,0.01)';
    'PWM2':
      PIN_NUMBER='(3)';
      OUTPUT_LOAD='(1.0,-1.0)';
    'CS2':
      PIN_NUMBER='(28)';
      INPUT_LOAD='(-0.01,0.01)';
    'OCP_L':
      PIN_NUMBER='(33)';
      OUTPUT_LOAD='(1.0,-1.0)';
    'TH_GND':
      PIN_NUMBER='(TH)';
      PINUSE='POWER';
      NO_LOAD_CHECK='Both';
      NO_IO_CHECK='Both';
      NO_ASSERT_CHECK='TRUE';
      NO_DIR_CHECK='TRUE';
      ALLOW_CONNECT='TRUE';
    'EN1||ADDR_CFG':
      PIN_NUMBER='(34)';
      INPUT_LOAD='(-0.01,0.01)';
    'TEMP1':
      PIN_NUMBER='(35)';
      INPUT_LOAD='(-0.01,0.01)';
    'PWM0':
      PIN_NUMBER='(1)';
      OUTPUT_LOAD='(1.0,-1.0)';
    'CS0':
      PIN_NUMBER='(30)';
      INPUT_LOAD='(-0.01,0.01)';
  end_pin;
  body
    PART_NAME='RAA229621GNPHA0';
    BODY_NAME='RAA229621GNPHA0';
    PHYS_DES_PREFIX='U';
    CLASS='IC';
  end_body;
end_primitive;

END.
